(kicad_pcb
	(version 20221018)
	(generator pcbnew)
	(general
    (thickness 1.6)
  )
	(paper "A4")
	(title_block
    (title "NUC Computer Cluster Power Breakout HW")
    (date "2023-10-18")
    (rev "1.4.3")
    (company "Antmicro Ltd.")
		(comment 9 "footprints 159-165 of 234")
	)
	(layers
    (0 "F.Cu" mixed)
    (1 "In1.Cu" power)
    (2 "In2.Cu" mixed)
    (31 "B.Cu" power)
    (32 "B.Adhes" user "B.Adhesive")
    (33 "F.Adhes" user "F.Adhesive")
    (34 "B.Paste" user)
    (35 "F.Paste" user)
    (36 "B.SilkS" user "B.Silkscreen")
    (37 "F.SilkS" user "F.Silkscreen")
    (38 "B.Mask" user)
    (39 "F.Mask" user)
    (40 "Dwgs.User" user "User.Drawings")
    (41 "Cmts.User" user "User.Comments")
    (42 "Eco1.User" user "User.Eco1")
    (43 "Eco2.User" user "User.Eco2")
    (44 "Edge.Cuts" user)
    (45 "Margin" user)
    (46 "B.CrtYd" user "B.Courtyard")
    (47 "F.CrtYd" user "F.Courtyard")
    (48 "B.Fab" user)
    (49 "F.Fab" user)
  )
	(footprint "antmicro-footprints:LED_0603_1608Metric_G" (layer "F.Cu")
    (at 163.2 53.85)
    (descr "LED SMD 0603 Green")
    (tags "LED SMD 0603 Green")
    (property "Author" "Antmicro")
    (property "Color" "Green")
    (property "License" "Apache-2.0")
    (property "MPN" "LG L29K-G2J1-24-Z")
    (property "Manufacturer" "OSRAM")
    (property "Sheetfile" "d1600e-psu-breakout-board.kicad_sch")
    (property "Sheetname" "")
    (property "ki_description" "LED, Green, SMD, 0603, 20 mA, 1.7 V, 570 nm")
    (property "ki_keywords" "SMT, DIODE, SEMICONDUCTOR, LED")
    (zone_connect 1)
    (attr smd)
    (fp_text reference "D7" (at -0.9 1.65) (layer "F.SilkS")
        (effects (font (size 0.7 0.7) (thickness 0.15)) (justify left bottom))
    )
    (fp_text value "LED_G_0603_LG_L29K-G2J1-24-Z" (at -0.001 1.599) (layer "F.Fab")
        (effects (font (size 0.7 0.7) (thickness 0.15)) (justify left bottom))
    )
    (fp_text user "${REFERENCE}" (at -1.4224 5.999) (layer "F.Fab") hide
        (effects (font (size 0.7 0.7) (thickness 0.15)) (justify left bottom))
    )
    (fp_text user "License: Apache-2.0" (at -1.4224 3.599) (layer "F.Fab") hide
        (effects (font (size 0.7 0.7) (thickness 0.15)) (justify left bottom))
    )
    (fp_text user "Author: Antmicro" (at -1.4224 4.799) (layer "F.Fab") hide
        (effects (font (size 0.7 0.7) (thickness 0.15)) (justify left bottom))
    )
    (fp_line (start -1.18 -0.319) (end -1.18 0.321)
      (stroke (width 0.15) (type solid)) (layer "F.SilkS"))
    (fp_line (start -0.094672 0.001008) (end -0.24 0.001008)
      (stroke (width 0.1) (type solid)) (layer "F.SilkS"))
    (fp_line (start -0.094672 0.001008) (end 0.105328 -0.198992)
      (stroke (width 0.1) (type solid)) (layer "F.SilkS"))
    (fp_line (start -0.094672 0.201008) (end -0.094672 -0.198992)
      (stroke (width 0.1) (type solid)) (layer "F.SilkS"))
    (fp_line (start 0.105328 0.001008) (end 0.24 0.001)
      (stroke (width 0.1) (type solid)) (layer "F.SilkS"))
    (fp_line (start 0.105328 0.201008) (end -0.094672 0.001008)
      (stroke (width 0.1) (type solid)) (layer "F.SilkS"))
    (fp_line (start 0.105328 0.201008) (end 0.105328 -0.198992)
      (stroke (width 0.1) (type solid)) (layer "F.SilkS"))
    (fp_line (start 0.22 -0.35) (end -0.22 -0.35)
      (stroke (width 0.15) (type solid)) (layer "F.SilkS"))
    (fp_line (start 0.22 0.35) (end -0.22 0.35)
      (stroke (width 0.15) (type solid)) (layer "F.SilkS"))
    (fp_rect (start 1.25 0.65) (end -1.25 -0.65)
      (stroke (width 0.05) (type solid)) (fill none) (layer "F.CrtYd"))
    (fp_line (start -0.199 -0.202) (end -0.199 0.1)
      (stroke (width 0.15) (type solid)) (layer "F.Fab"))
    (fp_line (start -0.199 0) (end -0.597 0)
      (stroke (width 0.15) (type solid)) (layer "F.Fab"))
    (fp_line (start -0.199 0.2) (end -0.199 0.1)
      (stroke (width 0.15) (type solid)) (layer "F.Fab"))
    (fp_line (start -0.101 0) (end 0.201 0.2)
      (stroke (width 0.15) (type solid)) (layer "F.Fab"))
    (fp_line (start 0.201 -0.202) (end -0.101 0)
      (stroke (width 0.15) (type solid)) (layer "F.Fab"))
    (fp_line (start 0.201 0) (end 0.201 -0.202)
      (stroke (width 0.15) (type solid)) (layer "F.Fab"))
    (fp_line (start 0.201 0.2) (end 0.201 0)
      (stroke (width 0.15) (type solid)) (layer "F.Fab"))
    (fp_line (start 0.599 0) (end 0.201 0)
      (stroke (width 0.15) (type solid)) (layer "F.Fab"))
    (fp_rect (start 0.848 0.4) (end -0.85 -0.402)
      (stroke (width 0.15) (type solid)) (fill none) (layer "F.Fab"))
    (pad "1" smd roundrect (at -0.7 0 180) (size 0.8 1) (layers "F.Cu" "F.Paste" "F.Mask") (roundrect_rratio 0.2)
      (net 4 "GND") (pinfunction "C") (pintype "passive"))
    (pad "2" smd roundrect (at 0.7 0 180) (size 0.8 1) (layers "F.Cu" "F.Paste" "F.Mask") (roundrect_rratio 0.2)
      (net 52 "Net-(D7-A)") (pinfunction "A") (pintype "passive"))
  )
	(footprint "antmicro-footprints:TPD2E009DRTR" (layer "F.Cu")
    (at 182.3375 111.7 180)
    (property "Author" "Antmicro")
    (property "License" "Apache-2.0")
    (property "MPN" "PESD5V0S2BQA")
    (property "Manufacturer" "Nexperia")
    (property "Sheetfile" "ftdi-module.kicad_sch")
    (property "Sheetname" "FTDI")
    (property "ki_description" "TVS diode array, 30 kV, SOT-1215, 5V, 45 pF")
    (property "ki_keywords" "SMT, DIODE, SEMICONDUCTOR, TVS, ESD")
    (attr smd)
    (fp_text reference "D14" (at 3.2875 -0.7 180) (layer "F.SilkS")
        (effects (font (size 0.7 0.7) (thickness 0.15)) (justify left bottom))
    )
    (fp_text value "PESD5V0S2BQA" (at 5.608 1.306 180) (layer "F.Fab")
        (effects (font (size 0.7 0.7) (thickness 0.15)) (justify left bottom))
    )
    (fp_text user "License: Apache-2.0" (at -0.949 5.706 180) (layer "F.Fab") hide
        (effects (font (size 0.7 0.7) (thickness 0.15)) (justify left bottom))
    )
    (fp_text user "Author: Antmicro" (at -0.949 3.306 180) (layer "F.Fab") hide
        (effects (font (size 0.7 0.7) (thickness 0.15)) (justify left bottom))
    )
    (fp_text user "${REFERENCE}" (at -0.949 4.506 180) (layer "F.Fab") hide
        (effects (font (size 0.7 0.7) (thickness 0.15)) (justify left bottom))
    )
    (fp_line (start 0.03 -0.499) (end 0.4 -0.499)
      (stroke (width 0.15) (type solid)) (layer "F.SilkS"))
    (fp_line (start 0.03 0.499) (end 0.4 0.499)
      (stroke (width 0.15) (type solid)) (layer "F.SilkS"))
    (fp_line (start 0.4 -0.419) (end 0.4 -0.499)
      (stroke (width 0.15) (type solid)) (layer "F.SilkS"))
    (fp_line (start 0.4 0.42) (end 0.4 0.499)
      (stroke (width 0.15) (type solid)) (layer "F.SilkS"))
    (fp_circle (center -0.5 -0.6) (end -0.45 -0.6)
      (stroke (width 0.15) (type solid)) (fill solid) (layer "F.SilkS"))
    (fp_rect (start -0.8 -0.59) (end 0.8 0.59)
      (stroke (width 0.05) (type solid)) (fill none) (layer "F.CrtYd"))
    (fp_line (start -0.4 -0.499) (end 0.4 -0.499)
      (stroke (width 0.15) (type solid)) (layer "F.Fab"))
    (fp_line (start -0.4 0.499) (end -0.4 -0.499)
      (stroke (width 0.15) (type solid)) (layer "F.Fab"))
    (fp_line (start 0.4 -0.499) (end 0.4 0.499)
      (stroke (width 0.15) (type solid)) (layer "F.Fab"))
    (fp_line (start 0.4 0.499) (end -0.4 0.499)
      (stroke (width 0.15) (type solid)) (layer "F.Fab"))
    (pad "1" smd rect (at -0.52 -0.349 180) (size 0.46 0.2) (layers "F.Cu" "F.Paste" "F.Mask")
      (net 10 "VBUS") (pinfunction "IO1") (pintype "passive"))
    (pad "2" smd rect (at -0.52 0.348 180) (size 0.46 0.2) (layers "F.Cu" "F.Paste" "F.Mask")
      (net 10 "VBUS") (pinfunction "IO2") (pintype "passive"))
    (pad "3" smd rect (at 0.52 0 180) (size 0.46 0.2) (layers "F.Cu" "F.Paste" "F.Mask")
      (net 77 "GNDD") (pinfunction "GND") (pintype "passive"))
  )
	(footprint "antmicro-footprints:R_0402_1005Metric" (layer "F.Cu")
    (at 145.25 96.59)
    (descr "Resistor SMD 0402")
    (tags "resistor SMD 0402")
    (property "Author" "Antmicro")
    (property "Current" "1A")
    (property "License" "Apache-2.0")
    (property "MPN" "ERJ2GE0R00X")
    (property "Manufacturer" "Panasonic")
    (property "Sheetfile" "pow-cycl-curr-meas.kicad_sch")
    (property "Sheetname" "Power Cycling & Current Measurement")
    (property "Tolerance" "")
    (property "Val" "0R")
    (property "ki_description" "SMD Chip Resistor, Jumper, 0 ohm, 100 mW, 0402 [1005 Metric], Thick Film, General Purpose")
    (property "ki_keywords" "0402, SMT, RESISTOR, PASSIVE")
    (attr smd)
    (fp_text reference "R70" (at -1 -0.49) (layer "F.SilkS")
        (effects (font (size 0.7 0.7) (thickness 0.15)) (justify left bottom))
    )
    (fp_text value "R_0R_0402" (at -1.011843 1.772047) (layer "F.Fab")
        (effects (font (size 0.7 0.7) (thickness 0.15)) (justify left bottom))
    )
    (fp_text user "Author: Antmicro" (at -0.95 4.169) (layer "F.Fab") hide
        (effects (font (size 0.7 0.7) (thickness 0.15)) (justify left bottom))
    )
    (fp_text user "License: Apache-2.0" (at -0.95 5.169) (layer "F.Fab") hide
        (effects (font (size 0.7 0.7) (thickness 0.15)) (justify left bottom))
    )
    (fp_text user "${REFERENCE}" (at -0.95 3.168) (layer "F.Fab") hide
        (effects (font (size 0.7 0.7) (thickness 0.15)) (justify left bottom))
    )
    (fp_rect (start -0.925 -0.47) (end 0.925 0.47)
      (stroke (width 0.05) (type default)) (fill none) (layer "F.CrtYd"))
    (fp_rect (start -0.5 -0.25) (end 0.5 0.25)
      (stroke (width 0.15) (type solid)) (fill none) (layer "F.Fab"))
    (pad "1" smd roundrect (at -0.48 0) (size 0.59 0.64) (layers "F.Cu" "F.Paste" "F.Mask") (roundrect_rratio 0.25)
      (net 144 "Net-(R2-Pad1)") (pintype "passive"))
    (pad "2" smd roundrect (at 0.48 0) (size 0.59 0.64) (layers "F.Cu" "F.Paste" "F.Mask") (roundrect_rratio 0.25)
      (net 90 "/Power Cycling & Current Measurement/V_ADC1") (pintype "passive"))
  )
	(footprint "antmicro-footprints:R_0603_1608Metric" (layer "F.Cu")
    (at 131.2 53.85)
    (descr "Resistor SMD 0603")
    (tags "resistor SMD 0603")
    (property "Author" "Antmicro")
    (property "License" "Apache-2.0")
    (property "MPN" "CR0603-FX-4701ELF")
    (property "Manufacturer" "Bourns")
    (property "Sheetfile" "d1600e-psu-breakout-board.kicad_sch")
    (property "Sheetname" "")
    (property "Tolerance" "1%")
    (property "Val" "4k7")
    (property "ki_description" "SMD Chip Resistor, 4.7 kohm, ± 1%, 100 mW, 0603 [1608 Metric], Thick Film, General Purpose")
    (property "ki_keywords" "0603, SMT, RESISTOR, PASSIVE")
    (attr smd)
    (fp_text reference "R12" (at -1.1 1.65) (layer "F.SilkS")
        (effects (font (size 0.7 0.7) (thickness 0.15)) (justify left bottom))
    )
    (fp_text value "R_4k7_0603" (at 0 1.6) (layer "F.Fab")
        (effects (font (size 0.7 0.7) (thickness 0.15)) (justify left bottom))
    )
    (fp_text user "License: Apache-2.0" (at -1.25 5.9) (layer "F.Fab") hide
        (effects (font (size 0.7 0.7) (thickness 0.15)) (justify left bottom))
    )
    (fp_text user "Author: Antmicro" (at -1.25 4.9) (layer "F.Fab") hide
        (effects (font (size 0.7 0.7) (thickness 0.15)) (justify left bottom))
    )
    (fp_text user "${REFERENCE}" (at -1.25 3.898) (layer "F.Fab") hide
        (effects (font (size 0.7 0.7) (thickness 0.15)) (justify left bottom))
    )
    (fp_line (start -0.15 -0.4) (end 0.15 -0.4)
      (stroke (width 0.15) (type solid)) (layer "F.SilkS"))
    (fp_line (start -0.15 0.4) (end 0.15 0.4)
      (stroke (width 0.15) (type solid)) (layer "F.SilkS"))
    (fp_rect (start -1.25 -0.65) (end 1.25 0.65)
      (stroke (width 0.05) (type solid)) (fill none) (layer "F.CrtYd"))
    (fp_rect (start -0.8 -0.4) (end 0.8 0.4)
      (stroke (width 0.15) (type solid)) (fill none) (layer "F.Fab"))
    (pad "1" smd roundrect (at -0.7 0) (size 0.8 1) (layers "F.Cu" "F.Paste" "F.Mask") (roundrect_rratio 0.2)
      (net 37 "Net-(D4-A)") (pintype "passive"))
    (pad "2" smd roundrect (at 0.7 0) (size 0.8 1) (layers "F.Cu" "F.Paste" "F.Mask") (roundrect_rratio 0.2)
      (net 44 "LOAD_2") (pintype "passive"))
  )
	(footprint "antmicro-footprints:R_0402_1005Metric" (layer "F.Cu")
    (at 179.85 101.12)
    (descr "Resistor SMD 0402")
    (tags "resistor SMD 0402")
    (property "Author" "Antmicro")
    (property "Current" "1A")
    (property "License" "Apache-2.0")
    (property "MPN" "ERJ2GE0R00X")
    (property "Manufacturer" "Panasonic")
    (property "Sheetfile" "d1600e-psu-breakout-board.kicad_sch")
    (property "Sheetname" "")
    (property "Tolerance" "")
    (property "Val" "0R")
    (property "ki_description" "SMD Chip Resistor, Jumper, 0 ohm, 100 mW, 0402 [1005 Metric], Thick Film, General Purpose")
    (property "ki_keywords" "0402, SMT, RESISTOR, PASSIVE")
    (attr smd)
    (fp_text reference "R72" (at -1.122484 1.27) (layer "F.SilkS")
        (effects (font (size 0.7 0.7) (thickness 0.15)) (justify left bottom))
    )
    (fp_text value "R_0R_0402" (at -1.011843 1.772047) (layer "F.Fab")
        (effects (font (size 0.7 0.7) (thickness 0.15)) (justify left bottom))
    )
    (fp_text user "${REFERENCE}" (at -0.95 3.168) (layer "F.Fab") hide
        (effects (font (size 0.7 0.7) (thickness 0.15)) (justify left bottom))
    )
    (fp_text user "License: Apache-2.0" (at -0.95 5.169) (layer "F.Fab") hide
        (effects (font (size 0.7 0.7) (thickness 0.15)) (justify left bottom))
    )
    (fp_text user "Author: Antmicro" (at -0.95 4.169) (layer "F.Fab") hide
        (effects (font (size 0.7 0.7) (thickness 0.15)) (justify left bottom))
    )
    (fp_rect (start -0.925 -0.47) (end 0.925 0.47)
      (stroke (width 0.05) (type default)) (fill none) (layer "F.CrtYd"))
    (fp_rect (start -0.5 -0.25) (end 0.5 0.25)
      (stroke (width 0.15) (type solid)) (fill none) (layer "F.Fab"))
    (pad "1" smd roundrect (at -0.48 0) (size 0.59 0.64) (layers "F.Cu" "F.Paste" "F.Mask") (roundrect_rratio 0.25)
      (net 145 "LED_DATA") (pintype "passive"))
    (pad "2" smd roundrect (at 0.48 0) (size 0.59 0.64) (layers "F.Cu" "F.Paste" "F.Mask") (roundrect_rratio 0.25)
      (net 99 "SDA_CON") (pintype "passive"))
  )
	(footprint "antmicro-footprints:R_0402_1005Metric" (layer "F.Cu")
    (at 187.4 107.65 180)
    (descr "Resistor SMD 0402")
    (tags "resistor SMD 0402")
    (property "Author" "Antmicro")
    (property "License" "Apache-2.0")
    (property "MPN" "CR0402-FX-5101GLF")
    (property "Manufacturer" "Bourns")
    (property "Sheetfile" "ftdi-module.kicad_sch")
    (property "Sheetname" "FTDI")
    (property "Tolerance" "1%")
    (property "Val" "5k1")
    (property "ki_description" "SMD Chip Resistor, 5.1 kohm, ± 1%, 63 mW, 0402 [1005 Metric], Thick Film, General Purpose")
    (property "ki_keywords" "0402, SMT, RESISTOR, PASSIVE")
    (attr smd)
    (fp_text reference "R58" (at 0.05 1) (layer "F.SilkS")
        (effects (font (size 0.7 0.7) (thickness 0.15)))
    )
    (fp_text value "R_5k1_0402" (at 0 1.17) (layer "F.Fab") hide
        (effects (font (size 1 1) (thickness 0.15)))
    )
    (fp_text user "Author: Antmicro" (at -0.95 4.169 180) (layer "F.Fab") hide
        (effects (font (size 0.7 0.7) (thickness 0.15)) (justify left bottom))
    )
    (fp_text user "${REFERENCE}" (at 0 0) (layer "F.Fab")
        (effects (font (size 0.25 0.25) (thickness 0.04)))
    )
    (fp_text user "License: Apache-2.0" (at -0.95 5.169 180) (layer "F.Fab") hide
        (effects (font (size 0.7 0.7) (thickness 0.15)) (justify left bottom))
    )
    (fp_rect (start -0.925 -0.47) (end 0.925 0.47)
      (stroke (width 0.05) (type default)) (fill none) (layer "F.CrtYd"))
    (fp_rect (start -0.5 -0.25) (end 0.5 0.25)
      (stroke (width 0.15) (type solid)) (fill none) (layer "F.Fab"))
    (pad "1" smd roundrect (at -0.48 0 180) (size 0.59 0.64) (layers "F.Cu" "F.Paste" "F.Mask") (roundrect_rratio 0.25)
      (net 114 "Net-(U1-CC_{2})") (pintype "passive"))
    (pad "2" smd roundrect (at 0.48 0 180) (size 0.59 0.64) (layers "F.Cu" "F.Paste" "F.Mask") (roundrect_rratio 0.25)
      (net 77 "GNDD") (pintype "passive"))
  )
	(footprint "antmicro-footprints:R_0603_1608Metric" (layer "F.Cu")
    (at 96.9 104.4)
    (descr "Resistor SMD 0603")
    (tags "resistor SMD 0603")
    (property "Author" "Antmicro")
    (property "License" "Apache-2.0")
    (property "MPN" "CR0603-FX-2201ELF")
    (property "Manufacturer" "Bourns")
    (property "Sheetfile" "d1600e-psu-breakout-board.kicad_sch")
    (property "Sheetname" "")
    (property "Tolerance" "1%")
    (property "Val" "2k2")
    (property "ki_description" "SMD Chip Resistor, 2.2 kohm, ± 1%, 100 mW, 0603 [1608 Metric], Thick Film, General Purpose")
    (property "ki_keywords" "0603, SMT, RESISTOR, PASSIVE")
    (attr smd)
    (fp_text reference "R56" (at -1.2 -0.55) (layer "F.SilkS")
        (effects (font (size 0.7 0.7) (thickness 0.15)) (justify left bottom))
    )
    (fp_text value "R_2k2_0603" (at 0 1.6) (layer "F.Fab")
        (effects (font (size 0.7 0.7) (thickness 0.15)) (justify left bottom))
    )
    (fp_text user "License: Apache-2.0" (at -1.25 5.9) (layer "F.Fab") hide
        (effects (font (size 0.7 0.7) (thickness 0.15)) (justify left bottom))
    )
    (fp_text user "Author: Antmicro" (at -1.25 4.9) (layer "F.Fab") hide
        (effects (font (size 0.7 0.7) (thickness 0.15)) (justify left bottom))
    )
    (fp_text user "${REFERENCE}" (at -1.25 3.898) (layer "F.Fab") hide
        (effects (font (size 0.7 0.7) (thickness 0.15)) (justify left bottom))
    )
    (fp_line (start -0.15 -0.4) (end 0.15 -0.4)
      (stroke (width 0.15) (type solid)) (layer "F.SilkS"))
    (fp_line (start -0.15 0.4) (end 0.15 0.4)
      (stroke (width 0.15) (type solid)) (layer "F.SilkS"))
    (fp_rect (start -1.25 -0.65) (end 1.25 0.65)
      (stroke (width 0.05) (type solid)) (fill none) (layer "F.CrtYd"))
    (fp_rect (start -0.8 -0.4) (end 0.8 0.4)
      (stroke (width 0.15) (type solid)) (fill none) (layer "F.Fab"))
    (pad "1" smd roundrect (at -0.7 0) (size 0.8 1) (layers "F.Cu" "F.Paste" "F.Mask") (roundrect_rratio 0.2)
      (net 82 "Net-(D11-A)") (pintype "passive"))
    (pad "2" smd roundrect (at 0.7 0) (size 0.8 1) (layers "F.Cu" "F.Paste" "F.Mask") (roundrect_rratio 0.2)
      (net 11 "VCC12V0") (pintype "passive"))
  )
)
